#ISCELL
  mstr_misc dns *
  *
#ISCELL
  mstr_symbols cad_note *
  *
#ISCELL
  mstr_symbols design_note *
  *
#ISCELL
  mstr_symbols intel_corp_bpage *
  *
#CELL
  mstr_digital gtl2014 *
  page152_i1
#ISCELL
  mstr_standard offpage *
  page152_i10
#CELL
  mstr_discrete res *
  page152_i100
#ISCELL
  mstr_standard offpage *
  page152_i101
#CELL
  mstr_discrete res *
  page152_i102
#ISCELL
  mstr_standard offpage *
  page152_i11
#ISCELL
  mstr_standard offpage *
  page152_i12
#ISCELL
  mstr_standard offpage *
  page152_i13
#CELL
  mstr_discrete res *
  page152_i14
#CELL
  mstr_discrete res *
  page152_i15
#CELL
  mstr_discrete res *
  page152_i16
#ISCELL
  mstr_symbols gnd *
  page152_i17
#CELL
  mstr_discrete cap *
  page152_i18
#CELL
  mstr_discrete res *
  page152_i2
#ISCELL
  mstr_symbols gnd *
  page152_i20
#ISCELL
  mstr_standard offpage *
  page152_i21
#ISCELL
  mstr_standard offpage *
  page152_i22
#ISCELL
  mstr_standard offpage *
  page152_i23
#ISCELL
  mstr_standard offpage *
  page152_i24
#CELL
  mstr_discrete res *
  page152_i25
#CELL
  mstr_discrete res *
  page152_i26
#CELL
  dev_discrete cap_a *
  page152_i27
#ISCELL
  mstr_symbols pvccio_cpu0 *
  page152_i28
#ISCELL
  mstr_symbols gnd *
  page152_i29
#ISCELL
  mstr_symbols gnd *
  page152_i3
#ISCELL
  mstr_standard offpage *
  page152_i30
#ISCELL
  mstr_standard offpage *
  page152_i4
#CELL
  mstr_discrete res *
  page152_i45
#CELL
  mstr_discrete res *
  page152_i47
#CELL
  mstr_discrete res *
  page152_i49
#ISCELL
  mstr_symbols p3v3 *
  page152_i5
#CELL
  mstr_discrete res *
  page152_i50
#CELL
  mstr_discrete res *
  page152_i51
#ISCELL
  mstr_symbols pvccio_cpu0 *
  page152_i52
#CELL
  mstr_discrete res *
  page152_i53
#CELL
  mstr_discrete res *
  page152_i54
#ISCELL
  mstr_symbols pvccio_cpu1 *
  page152_i55
#CELL
  mstr_discrete res *
  page152_i56
#CELL
  mstr_discrete res *
  page152_i57
#CELL
  mstr_discrete res *
  page152_i58
#CELL
  mstr_discrete res *
  page152_i59
#CELL
  mstr_discrete res *
  page152_i6
#ISCELL
  mstr_symbols pvccio_cpu0 *
  page152_i60
#CELL
  mstr_discrete res *
  page152_i61
#CELL
  mstr_discrete res *
  page152_i62
#ISCELL
  mstr_symbols pvccio_cpu1 *
  page152_i63
#CELL
  mstr_discrete res *
  page152_i64
#CELL
  mstr_discrete res *
  page152_i65
#CELL
  mstr_discrete res *
  page152_i66
#CELL
  mstr_discrete res *
  page152_i67
#CELL
  mstr_discrete res *
  page152_i68
#CELL
  mstr_discrete res *
  page152_i69
#CELL
  mstr_discrete res *
  page152_i70
#CELL
  mstr_discrete res *
  page152_i71
#CELL
  mstr_discrete res *
  page152_i72
#CELL
  mstr_discrete res *
  page152_i73
#CELL
  mstr_discrete res *
  page152_i74
#ISCELL
  mstr_standard offpage *
  page152_i75
#ISCELL
  mstr_standard offpage *
  page152_i76
#ISCELL
  mstr_standard offpage *
  page152_i77
#ISCELL
  mstr_standard offpage *
  page152_i78
#CELL
  mstr_discrete res *
  page152_i79
#ISCELL
  mstr_standard offpage *
  page152_i85
#ISCELL
  mstr_standard offpage *
  page152_i87
#ISCELL
  mstr_standard offpage *
  page152_i89
#ISCELL
  mstr_standard offpage *
  page152_i91
#CELL
  mstr_discrete res *
  page152_i92
#CELL
  mstr_discrete res *
  page152_i93
#CELL
  mstr_discrete res *
  page152_i94
#CELL
  mstr_discrete res *
  page152_i95
#ISCELL
  mstr_standard offpage *
  page152_i96
#ISCELL
  mstr_standard offpage *
  page152_i97
#CELL
  mstr_discrete res *
  page152_i98
#ISCELL
  mstr_standard offpage *
  page152_i99
